(kicad_pcb
	(version 20260206)
	(generator "pcbnew")
	(generator_version "10.0")
	(general
		(thickness 1.6)
		(legacy_teardrops no)
	)
	(paper "A4")
	(title_block
		(title "01162023_DA0F0TEBIF0_F0T_Expander_BD_F_brd_V02_OCP.brd")
		(comment 1 "Grand Teton / footprints 767-773 of 9728")
	)
	(layers
		(0 "F.Cu" signal "TOP")
		(4 "In1.Cu" signal "GND")
		(6 "In2.Cu" signal "VCC")
		(8 "In3.Cu" signal "VCC1")
		(10 "In4.Cu" signal "GND1")
		(12 "In5.Cu" signal "IN1")
		(14 "In6.Cu" signal "GND2")
		(16 "In7.Cu" signal "IN2")
		(18 "In8.Cu" signal "GND3")
		(20 "In9.Cu" signal "IN3")
		(22 "In10.Cu" signal "GND4")
		(24 "In11.Cu" signal "IN4")
		(26 "In12.Cu" signal "GND5")
		(28 "In13.Cu" signal "IN5")
		(30 "In14.Cu" signal "GND6")
		(32 "In15.Cu" signal "IN6")
		(34 "In16.Cu" signal "GND7")
		(2 "B.Cu" signal "BOTTOM")
		(9 "F.Adhes" user "F.Adhesive")
		(11 "B.Adhes" user "B.Adhesive")
		(13 "F.Paste" user "Package Geometry/Pastemask Top")
		(15 "B.Paste" user "Package Geometry/Pastemask Bottom")
		(5 "F.SilkS" user "Ref Des/Silkscreen Top")
		(7 "B.SilkS" user "Ref Des/Silkscreen Bottom")
		(1 "F.Mask" user "Board Geometry/Soldermask Top")
		(3 "B.Mask" user "Board Geometry/Soldermask Bottom")
		(17 "Dwgs.User" user "User.Drawings")
		(19 "Cmts.User" user "User.Comments")
		(21 "Eco1.User" user "User.Eco1")
		(23 "Eco2.User" user "User.Eco2")
		(25 "Edge.Cuts" user "Board Geometry/Outline")
		(27 "Margin" user)
		(31 "F.CrtYd" user "Package Geometry/Place Bound Top")
		(29 "B.CrtYd" user "Package Geometry/Place Bound Bottom")
		(35 "F.Fab" user "Ref Des/Assembly Top")
		(33 "B.Fab" user "Ref Des/Assembly Bottom")
	)
	(footprint ""
		(layer "F.Cu")
		(at 35.766248 -350.098614 90)
		(property "Reference" "C2167"
			(at 0 0 90)
			(layer "F.SilkS")
			(hide yes)
			(effects
				(font
					(size 1.27 1.27)
				)
			)
		)
		(property "Value" ""
			(at 0 0 90)
			(layer "F.Fab")
			(effects
				(font
					(size 1.27 1.27)
				)
			)
		)
		(duplicate_pad_numbers_are_jumpers no)
		(fp_line
			(start 0.299974 -0.150114)
			(end 0.299974 0.150114)
			(stroke
				(width 0.1)
				(type default)
			)
			(layer "F.Fab")
		)
		(fp_line
			(start -0.299974 -0.150114)
			(end 0.299974 -0.150114)
			(stroke
				(width 0.1)
				(type default)
			)
			(layer "F.Fab")
		)
		(fp_line
			(start 0.299974 0.150114)
			(end -0.299974 0.150114)
			(stroke
				(width 0.1)
				(type default)
			)
			(layer "F.Fab")
		)
		(fp_line
			(start -0.299974 0.150114)
			(end -0.299974 -0.150114)
			(stroke
				(width 0.1)
				(type default)
			)
			(layer "F.Fab")
		)
		(pad "1" smd rect
			(at -0.2667 0 90)
			(size 0.3048 0.381)
			(layers "F.Cu" "F.Mask" "F.Paste")
			(net "P5E_PEX0_STN4_TX_DN<72>")
		)
		(pad "2" smd rect
			(at 0.2667 0 90)
			(size 0.3048 0.381)
			(layers "F.Cu" "F.Mask" "F.Paste")
			(net "P5E_PEX0_STN4_TX_C_DN<72>")
		)
	)
	(footprint ""
		(layer "F.Cu")
		(at 319.003934 -289.230816 90)
		(property "Reference" "R3984"
			(at 0 0 90)
			(layer "F.SilkS")
			(hide yes)
			(effects
				(font
					(size 1.27 1.27)
				)
			)
		)
		(property "Value" ""
			(at 0 0 90)
			(layer "F.Fab")
			(effects
				(font
					(size 1.27 1.27)
				)
			)
		)
		(duplicate_pad_numbers_are_jumpers no)
		(fp_line
			(start 0.7874 -0.4064)
			(end 0.7874 0.4064)
			(stroke
				(width 0.1524)
				(type default)
			)
			(layer "F.SilkS")
		)
		(fp_line
			(start -0.7874 -0.4064)
			(end 0.7874 -0.4064)
			(stroke
				(width 0.1524)
				(type default)
			)
			(layer "F.SilkS")
		)
		(fp_line
			(start 0.7874 0.4064)
			(end -0.7874 0.4064)
			(stroke
				(width 0.1524)
				(type default)
			)
			(layer "F.SilkS")
		)
		(fp_line
			(start -0.7874 0.4064)
			(end -0.7874 -0.4064)
			(stroke
				(width 0.1524)
				(type default)
			)
			(layer "F.SilkS")
		)
		(fp_line
			(start -0.12065 -0.305054)
			(end -0.12065 -0.2794)
			(stroke
				(width 0.1)
				(type default)
			)
			(layer "F.Fab")
		)
		(fp_line
			(start -0.67945 -0.305054)
			(end -0.12065 -0.305054)
			(stroke
				(width 0.1)
				(type default)
			)
			(layer "F.Fab")
		)
		(fp_line
			(start 0.67945 -0.3048)
			(end 0.67945 0.3048)
			(stroke
				(width 0.1)
				(type default)
			)
			(layer "F.Fab")
		)
		(fp_line
			(start 0.12065 -0.3048)
			(end 0.67945 -0.3048)
			(stroke
				(width 0.1)
				(type default)
			)
			(layer "F.Fab")
		)
		(fp_line
			(start 0.12065 -0.2794)
			(end 0.12065 -0.3048)
			(stroke
				(width 0.1)
				(type default)
			)
			(layer "F.Fab")
		)
		(fp_line
			(start -0.12065 -0.2794)
			(end 0.12065 -0.2794)
			(stroke
				(width 0.1)
				(type default)
			)
			(layer "F.Fab")
		)
		(fp_line
			(start 0.120396 0.2794)
			(end -0.12065 0.2794)
			(stroke
				(width 0.1)
				(type default)
			)
			(layer "F.Fab")
		)
		(fp_line
			(start -0.12065 0.2794)
			(end -0.12065 0.3048)
			(stroke
				(width 0.1)
				(type default)
			)
			(layer "F.Fab")
		)
		(fp_line
			(start 0.67945 0.3048)
			(end 0.120396 0.3048)
			(stroke
				(width 0.1)
				(type default)
			)
			(layer "F.Fab")
		)
		(fp_line
			(start 0.120396 0.3048)
			(end 0.120396 0.2794)
			(stroke
				(width 0.1)
				(type default)
			)
			(layer "F.Fab")
		)
		(fp_line
			(start -0.12065 0.3048)
			(end -0.67945 0.3048)
			(stroke
				(width 0.1)
				(type default)
			)
			(layer "F.Fab")
		)
		(fp_line
			(start -0.67945 0.3048)
			(end -0.67945 -0.305054)
			(stroke
				(width 0.1)
				(type default)
			)
			(layer "F.Fab")
		)
		(pad "1" smd circle
			(at -0.40005 0 90)
			(size 0 0)
			(layers "F.Cu" "F.Mask" "F.Paste")
			(net "PWRGD_P1V8_PEX_R")
		)
		(pad "2" smd circle
			(at 0.40005 0 90)
			(size 0 0)
			(layers "F.Cu" "F.Mask" "F.Paste")
			(net "PWRGD_P1V8_PEX2_R")
		)
	)
	(footprint ""
		(layer "F.Cu")
		(at 270.960342 -116.7384)
		(property "Reference" "R243"
			(at 0 0 0)
			(layer "F.SilkS")
			(hide yes)
			(effects
				(font
					(size 1.27 1.27)
				)
			)
		)
		(property "Value" ""
			(at 0 0 0)
			(layer "F.Fab")
			(effects
				(font
					(size 1.27 1.27)
				)
			)
		)
		(duplicate_pad_numbers_are_jumpers no)
		(fp_line
			(start -0.7874 -0.4064)
			(end 0.7874 -0.4064)
			(stroke
				(width 0.1524)
				(type default)
			)
			(layer "F.SilkS")
		)
		(fp_line
			(start -0.7874 0.4064)
			(end -0.7874 -0.4064)
			(stroke
				(width 0.1524)
				(type default)
			)
			(layer "F.SilkS")
		)
		(fp_line
			(start 0.7874 -0.4064)
			(end 0.7874 0.4064)
			(stroke
				(width 0.1524)
				(type default)
			)
			(layer "F.SilkS")
		)
		(fp_line
			(start 0.7874 0.4064)
			(end -0.7874 0.4064)
			(stroke
				(width 0.1524)
				(type default)
			)
			(layer "F.SilkS")
		)
		(fp_line
			(start -0.67945 -0.305054)
			(end -0.12065 -0.305054)
			(stroke
				(width 0.1)
				(type default)
			)
			(layer "F.Fab")
		)
		(fp_line
			(start -0.67945 0.3048)
			(end -0.67945 -0.305054)
			(stroke
				(width 0.1)
				(type default)
			)
			(layer "F.Fab")
		)
		(fp_line
			(start -0.12065 -0.305054)
			(end -0.12065 -0.2794)
			(stroke
				(width 0.1)
				(type default)
			)
			(layer "F.Fab")
		)
		(fp_line
			(start -0.12065 -0.2794)
			(end 0.12065 -0.2794)
			(stroke
				(width 0.1)
				(type default)
			)
			(layer "F.Fab")
		)
		(fp_line
			(start -0.12065 0.2794)
			(end -0.12065 0.3048)
			(stroke
				(width 0.1)
				(type default)
			)
			(layer "F.Fab")
		)
		(fp_line
			(start -0.12065 0.3048)
			(end -0.67945 0.3048)
			(stroke
				(width 0.1)
				(type default)
			)
			(layer "F.Fab")
		)
		(fp_line
			(start 0.120396 0.2794)
			(end -0.12065 0.2794)
			(stroke
				(width 0.1)
				(type default)
			)
			(layer "F.Fab")
		)
		(fp_line
			(start 0.120396 0.3048)
			(end 0.120396 0.2794)
			(stroke
				(width 0.1)
				(type default)
			)
			(layer "F.Fab")
		)
		(fp_line
			(start 0.12065 -0.3048)
			(end 0.67945 -0.3048)
			(stroke
				(width 0.1)
				(type default)
			)
			(layer "F.Fab")
		)
		(fp_line
			(start 0.12065 -0.2794)
			(end 0.12065 -0.3048)
			(stroke
				(width 0.1)
				(type default)
			)
			(layer "F.Fab")
		)
		(fp_line
			(start 0.67945 -0.3048)
			(end 0.67945 0.3048)
			(stroke
				(width 0.1)
				(type default)
			)
			(layer "F.Fab")
		)
		(fp_line
			(start 0.67945 0.3048)
			(end 0.120396 0.3048)
			(stroke
				(width 0.1)
				(type default)
			)
			(layer "F.Fab")
		)
		(pad "1" smd circle
			(at -0.40005 0)
			(size 0 0)
			(layers "F.Cu" "F.Mask" "F.Paste")
			(net "PRSNT_NIC4_N")
		)
		(pad "2" smd circle
			(at 0.40005 0)
			(size 0 0)
			(layers "F.Cu" "F.Mask" "F.Paste")
			(net "PRSNTB0_NIC4_N")
		)
	)
	(footprint ""
		(layer "F.Cu")
		(at 381.587756 -301.220632)
		(property "Reference" "C3546"
			(at 0 0 0)
			(layer "F.SilkS")
			(hide yes)
			(effects
				(font
					(size 1.27 1.27)
				)
			)
		)
		(property "Value" ""
			(at 0 0 0)
			(layer "F.Fab")
			(effects
				(font
					(size 1.27 1.27)
				)
			)
		)
		(duplicate_pad_numbers_are_jumpers no)
		(fp_line
			(start -1.2954 -0.5842)
			(end 1.2954 -0.5842)
			(stroke
				(width 0.1524)
				(type default)
			)
			(layer "F.SilkS")
		)
		(fp_line
			(start -1.2954 0.5842)
			(end -1.2954 -0.5842)
			(stroke
				(width 0.1524)
				(type default)
			)
			(layer "F.SilkS")
		)
		(fp_line
			(start 1.2954 -0.5842)
			(end 1.2954 0.5842)
			(stroke
				(width 0.1524)
				(type default)
			)
			(layer "F.SilkS")
		)
		(fp_line
			(start 1.2954 0.5842)
			(end -1.2954 0.5842)
			(stroke
				(width 0.1524)
				(type default)
			)
			(layer "F.SilkS")
		)
		(fp_line
			(start -1.1938 -0.4064)
			(end -0.8636 -0.4064)
			(stroke
				(width 0.1)
				(type default)
			)
			(layer "F.Fab")
		)
		(fp_line
			(start -1.1938 0.4064)
			(end -1.1938 -0.4064)
			(stroke
				(width 0.1)
				(type default)
			)
			(layer "F.Fab")
		)
		(fp_line
			(start -0.8636 -0.4572)
			(end 0.8636 -0.4572)
			(stroke
				(width 0.1)
				(type default)
			)
			(layer "F.Fab")
		)
		(fp_line
			(start -0.8636 -0.4064)
			(end -0.8636 -0.4572)
			(stroke
				(width 0.1)
				(type default)
			)
			(layer "F.Fab")
		)
		(fp_line
			(start -0.8636 0.4064)
			(end -1.1938 0.4064)
			(stroke
				(width 0.1)
				(type default)
			)
			(layer "F.Fab")
		)
		(fp_line
			(start -0.8636 0.4572)
			(end -0.8636 0.4064)
			(stroke
				(width 0.1)
				(type default)
			)
			(layer "F.Fab")
		)
		(fp_line
			(start 0.8636 -0.4572)
			(end 0.8636 -0.4064)
			(stroke
				(width 0.1)
				(type default)
			)
			(layer "F.Fab")
		)
		(fp_line
			(start 0.8636 -0.4064)
			(end 1.1938 -0.4064)
			(stroke
				(width 0.1)
				(type default)
			)
			(layer "F.Fab")
		)
		(fp_line
			(start 0.8636 0.4064)
			(end 0.8636 0.4572)
			(stroke
				(width 0.1)
				(type default)
			)
			(layer "F.Fab")
		)
		(fp_line
			(start 0.8636 0.4572)
			(end -0.8636 0.4572)
			(stroke
				(width 0.1)
				(type default)
			)
			(layer "F.Fab")
		)
		(fp_line
			(start 1.1938 -0.4064)
			(end 1.1938 0.4064)
			(stroke
				(width 0.1)
				(type default)
			)
			(layer "F.Fab")
		)
		(fp_line
			(start 1.1938 0.4064)
			(end 0.8636 0.4064)
			(stroke
				(width 0.1)
				(type default)
			)
			(layer "F.Fab")
		)
		(pad "1" smd rect
			(at -0.7366 0 270)
			(size 0.7112 0.8128)
			(layers "F.Cu" "F.Mask" "F.Paste")
			(net "PCEPLL1_VDDA18_PEX3")
		)
		(pad "2" smd rect
			(at 0.7366 0 270)
			(size 0.7112 0.8128)
			(layers "F.Cu" "F.Mask" "F.Paste")
			(net "GND")
		)
	)
	(footprint ""
		(layer "F.Cu")
		(at 152.345898 -258.463034)
		(property "Reference" "C3219"
			(at 0 0 0)
			(layer "F.SilkS")
			(hide yes)
			(effects
				(font
					(size 1.27 1.27)
				)
			)
		)
		(property "Value" ""
			(at 0 0 0)
			(layer "F.Fab")
			(effects
				(font
					(size 1.27 1.27)
				)
			)
		)
		(duplicate_pad_numbers_are_jumpers no)
		(fp_line
			(start -1.2954 -0.5842)
			(end 1.2954 -0.5842)
			(stroke
				(width 0.1524)
				(type default)
			)
			(layer "F.SilkS")
		)
		(fp_line
			(start -1.2954 0.5842)
			(end -1.2954 -0.5842)
			(stroke
				(width 0.1524)
				(type default)
			)
			(layer "F.SilkS")
		)
		(fp_line
			(start 1.2954 -0.5842)
			(end 1.2954 0.5842)
			(stroke
				(width 0.1524)
				(type default)
			)
			(layer "F.SilkS")
		)
		(fp_line
			(start 1.2954 0.5842)
			(end -1.2954 0.5842)
			(stroke
				(width 0.1524)
				(type default)
			)
			(layer "F.SilkS")
		)
		(fp_line
			(start -1.1938 -0.4064)
			(end -0.8636 -0.4064)
			(stroke
				(width 0.1)
				(type default)
			)
			(layer "F.Fab")
		)
		(fp_line
			(start -1.1938 0.4064)
			(end -1.1938 -0.4064)
			(stroke
				(width 0.1)
				(type default)
			)
			(layer "F.Fab")
		)
		(fp_line
			(start -0.8636 -0.4572)
			(end 0.8636 -0.4572)
			(stroke
				(width 0.1)
				(type default)
			)
			(layer "F.Fab")
		)
		(fp_line
			(start -0.8636 -0.4064)
			(end -0.8636 -0.4572)
			(stroke
				(width 0.1)
				(type default)
			)
			(layer "F.Fab")
		)
		(fp_line
			(start -0.8636 0.4064)
			(end -1.1938 0.4064)
			(stroke
				(width 0.1)
				(type default)
			)
			(layer "F.Fab")
		)
		(fp_line
			(start -0.8636 0.4572)
			(end -0.8636 0.4064)
			(stroke
				(width 0.1)
				(type default)
			)
			(layer "F.Fab")
		)
		(fp_line
			(start 0.8636 -0.4572)
			(end 0.8636 -0.4064)
			(stroke
				(width 0.1)
				(type default)
			)
			(layer "F.Fab")
		)
		(fp_line
			(start 0.8636 -0.4064)
			(end 1.1938 -0.4064)
			(stroke
				(width 0.1)
				(type default)
			)
			(layer "F.Fab")
		)
		(fp_line
			(start 0.8636 0.4064)
			(end 0.8636 0.4572)
			(stroke
				(width 0.1)
				(type default)
			)
			(layer "F.Fab")
		)
		(fp_line
			(start 0.8636 0.4572)
			(end -0.8636 0.4572)
			(stroke
				(width 0.1)
				(type default)
			)
			(layer "F.Fab")
		)
		(fp_line
			(start 1.1938 -0.4064)
			(end 1.1938 0.4064)
			(stroke
				(width 0.1)
				(type default)
			)
			(layer "F.Fab")
		)
		(fp_line
			(start 1.1938 0.4064)
			(end 0.8636 0.4064)
			(stroke
				(width 0.1)
				(type default)
			)
			(layer "F.Fab")
		)
		(pad "1" smd rect
			(at -0.7366 0 270)
			(size 0.7112 0.8128)
			(layers "F.Cu" "F.Mask" "F.Paste")
			(net "PCEPLL5_VDDA18_PEX1")
		)
		(pad "2" smd rect
			(at 0.7366 0 270)
			(size 0.7112 0.8128)
			(layers "F.Cu" "F.Mask" "F.Paste")
			(net "GND")
		)
	)
	(footprint ""
		(layer "F.Cu")
		(at 120.815354 -59.546236 90)
		(property "Reference" "C2886"
			(at 0 0 90)
			(layer "F.SilkS")
			(hide yes)
			(effects
				(font
					(size 1.27 1.27)
				)
			)
		)
		(property "Value" ""
			(at 0 0 90)
			(layer "F.Fab")
			(effects
				(font
					(size 1.27 1.27)
				)
			)
		)
		(duplicate_pad_numbers_are_jumpers no)
		(fp_line
			(start 0.7874 -0.4064)
			(end 0.7874 0.4064)
			(stroke
				(width 0.1524)
				(type default)
			)
			(layer "F.SilkS")
		)
		(fp_line
			(start -0.7874 -0.4064)
			(end 0.7874 -0.4064)
			(stroke
				(width 0.1524)
				(type default)
			)
			(layer "F.SilkS")
		)
		(fp_line
			(start 0.7874 0.4064)
			(end -0.7874 0.4064)
			(stroke
				(width 0.1524)
				(type default)
			)
			(layer "F.SilkS")
		)
		(fp_line
			(start -0.7874 0.4064)
			(end -0.7874 -0.4064)
			(stroke
				(width 0.1524)
				(type default)
			)
			(layer "F.SilkS")
		)
		(fp_line
			(start -0.12065 -0.305054)
			(end -0.12065 -0.2794)
			(stroke
				(width 0.1)
				(type default)
			)
			(layer "F.Fab")
		)
		(fp_line
			(start -0.67945 -0.305054)
			(end -0.12065 -0.305054)
			(stroke
				(width 0.1)
				(type default)
			)
			(layer "F.Fab")
		)
		(fp_line
			(start 0.67945 -0.3048)
			(end 0.67945 0.3048)
			(stroke
				(width 0.1)
				(type default)
			)
			(layer "F.Fab")
		)
		(fp_line
			(start 0.12065 -0.3048)
			(end 0.67945 -0.3048)
			(stroke
				(width 0.1)
				(type default)
			)
			(layer "F.Fab")
		)
		(fp_line
			(start 0.12065 -0.2794)
			(end 0.12065 -0.3048)
			(stroke
				(width 0.1)
				(type default)
			)
			(layer "F.Fab")
		)
		(fp_line
			(start -0.12065 -0.2794)
			(end 0.12065 -0.2794)
			(stroke
				(width 0.1)
				(type default)
			)
			(layer "F.Fab")
		)
		(fp_line
			(start 0.120396 0.2794)
			(end -0.12065 0.2794)
			(stroke
				(width 0.1)
				(type default)
			)
			(layer "F.Fab")
		)
		(fp_line
			(start -0.12065 0.2794)
			(end -0.12065 0.3048)
			(stroke
				(width 0.1)
				(type default)
			)
			(layer "F.Fab")
		)
		(fp_line
			(start 0.67945 0.3048)
			(end 0.120396 0.3048)
			(stroke
				(width 0.1)
				(type default)
			)
			(layer "F.Fab")
		)
		(fp_line
			(start 0.120396 0.3048)
			(end 0.120396 0.2794)
			(stroke
				(width 0.1)
				(type default)
			)
			(layer "F.Fab")
		)
		(fp_line
			(start -0.12065 0.3048)
			(end -0.67945 0.3048)
			(stroke
				(width 0.1)
				(type default)
			)
			(layer "F.Fab")
		)
		(fp_line
			(start -0.67945 0.3048)
			(end -0.67945 -0.305054)
			(stroke
				(width 0.1)
				(type default)
			)
			(layer "F.Fab")
		)
		(pad "1" smd circle
			(at -0.40005 0 90)
			(size 0 0)
			(layers "F.Cu" "F.Mask" "F.Paste")
			(net "SSD4_AUX_P3V3_EN_R")
		)
		(pad "2" smd circle
			(at 0.40005 0 90)
			(size 0 0)
			(layers "F.Cu" "F.Mask" "F.Paste")
			(net "GND")
		)
	)
	(footprint ""
		(layer "F.Cu")
		(at 205.777592 -350.312482 90)
		(property "Reference" "R496"
			(at 0 0 90)
			(layer "F.SilkS")
			(hide yes)
			(effects
				(font
					(size 1.27 1.27)
				)
			)
		)
		(property "Value" ""
			(at 0 0 90)
			(layer "F.Fab")
			(effects
				(font
					(size 1.27 1.27)
				)
			)
		)
		(duplicate_pad_numbers_are_jumpers no)
		(fp_line
			(start 0.7874 -0.4064)
			(end 0.7874 0.4064)
			(stroke
				(width 0.1524)
				(type default)
			)
			(layer "F.SilkS")
		)
		(fp_line
			(start -0.7874 -0.4064)
			(end 0.7874 -0.4064)
			(stroke
				(width 0.1524)
				(type default)
			)
			(layer "F.SilkS")
		)
		(fp_line
			(start 0.7874 0.4064)
			(end -0.7874 0.4064)
			(stroke
				(width 0.1524)
				(type default)
			)
			(layer "F.SilkS")
		)
		(fp_line
			(start -0.7874 0.4064)
			(end -0.7874 -0.4064)
			(stroke
				(width 0.1524)
				(type default)
			)
			(layer "F.SilkS")
		)
		(fp_line
			(start -0.12065 -0.305054)
			(end -0.12065 -0.2794)
			(stroke
				(width 0.1)
				(type default)
			)
			(layer "F.Fab")
		)
		(fp_line
			(start -0.67945 -0.305054)
			(end -0.12065 -0.305054)
			(stroke
				(width 0.1)
				(type default)
			)
			(layer "F.Fab")
		)
		(fp_line
			(start 0.67945 -0.3048)
			(end 0.67945 0.3048)
			(stroke
				(width 0.1)
				(type default)
			)
			(layer "F.Fab")
		)
		(fp_line
			(start 0.12065 -0.3048)
			(end 0.67945 -0.3048)
			(stroke
				(width 0.1)
				(type default)
			)
			(layer "F.Fab")
		)
		(fp_line
			(start 0.12065 -0.2794)
			(end 0.12065 -0.3048)
			(stroke
				(width 0.1)
				(type default)
			)
			(layer "F.Fab")
		)
		(fp_line
			(start -0.12065 -0.2794)
			(end 0.12065 -0.2794)
			(stroke
				(width 0.1)
				(type default)
			)
			(layer "F.Fab")
		)
		(fp_line
			(start 0.120396 0.2794)
			(end -0.12065 0.2794)
			(stroke
				(width 0.1)
				(type default)
			)
			(layer "F.Fab")
		)
		(fp_line
			(start -0.12065 0.2794)
			(end -0.12065 0.3048)
			(stroke
				(width 0.1)
				(type default)
			)
			(layer "F.Fab")
		)
		(fp_line
			(start 0.67945 0.3048)
			(end 0.120396 0.3048)
			(stroke
				(width 0.1)
				(type default)
			)
			(layer "F.Fab")
		)
		(fp_line
			(start 0.120396 0.3048)
			(end 0.120396 0.2794)
			(stroke
				(width 0.1)
				(type default)
			)
			(layer "F.Fab")
		)
		(fp_line
			(start -0.12065 0.3048)
			(end -0.67945 0.3048)
			(stroke
				(width 0.1)
				(type default)
			)
			(layer "F.Fab")
		)
		(fp_line
			(start -0.67945 0.3048)
			(end -0.67945 -0.305054)
			(stroke
				(width 0.1)
				(type default)
			)
			(layer "F.Fab")
		)
		(pad "1" smd circle
			(at -0.40005 0 90)
			(size 0 0)
			(layers "F.Cu" "F.Mask" "F.Paste")
			(net "P3V3_AUX")
		)
		(pad "2" smd circle
			(at 0.40005 0 90)
			(size 0 0)
			(layers "F.Cu" "F.Mask" "F.Paste")
			(net "HSC_D_OC_BUF_N")
		)
	)
)
